(kicad_pcb
	(version 20241229)
	(generator "pcbnew")
	(generator_version "9.0")
	(general
		(thickness 1.552)
		(legacy_teardrops no)
	)
	(paper "A4")
	(title_block
		(date "2023-07-25")
		(rev "1.1.4")
		(comment 9 "footprints 262-266 of 379")
	)
	(layers
		(0 "F.Cu" signal)
		(4 "In1.Cu" signal)
		(6 "In2.Cu" signal)
		(8 "In3.Cu" signal)
		(10 "In4.Cu" signal)
		(12 "In5.Cu" signal)
		(14 "In6.Cu" signal)
		(2 "B.Cu" signal)
		(9 "F.Adhes" user "F.Adhesive")
		(11 "B.Adhes" user "B.Adhesive")
		(13 "F.Paste" user)
		(15 "B.Paste" user)
		(5 "F.SilkS" user "F.Silkscreen")
		(7 "B.SilkS" user "B.Silkscreen")
		(1 "F.Mask" user)
		(3 "B.Mask" user)
		(17 "Dwgs.User" user "User.Drawings")
		(19 "Cmts.User" user "User.Comments")
		(21 "Eco1.User" user "User.Eco1")
		(23 "Eco2.User" user "User.Eco2")
		(25 "Edge.Cuts" user)
		(27 "Margin" user)
		(31 "F.CrtYd" user "F.Courtyard")
		(29 "B.CrtYd" user "B.Courtyard")
		(35 "F.Fab" user)
		(33 "B.Fab" user)
	)
	(footprint "antmicro-footprints:C_0201"
		(layer "B.Cu")
		(at 129.1 91.9 180)
		(descr "Capacitor SMD 0201")
		(tags "capacitor SMD 0201")
		(property "Reference" "C58"
			(at 8.27 12.695736 0)
			(layer "B.SilkS")
			(effects
				(font
					(size 0.65 0.65)
					(thickness 0.15)
				)
				(justify left bottom mirror)
			)
		)
		(property "Value" "C_100n_0201"
			(at 0 -1.4 0)
			(layer "B.Fab")
			(hide yes)
			(effects
				(font
					(size 0.7 0.7)
					(thickness 0.15)
				)
				(justify left bottom mirror)
			)
		)
		(property "Datasheet" "https://www.yageo.com/en/Chart/Download/pdf/CC0201KRX6S5BB104"
			(at 0 0 180)
			(layer "F.Fab")
			(hide yes)
			(effects
				(font
					(size 1.27 1.27)
					(thickness 0.15)
				)
			)
		)
		(property "Description" "SMD Multilayer Ceramic Capacitor, 0.1 µF, 6.3 V, 0201 [0603 Metric], ± 10%, X6S, CC Series"
			(at 0 0 180)
			(layer "F.Fab")
			(hide yes)
			(effects
				(font
					(size 1.27 1.27)
					(thickness 0.15)
				)
			)
		)
		(property "Author" "Antmicro"
			(at 258.2 183.8 0)
			(layer "B.Fab")
			(hide yes)
			(effects
				(font
					(size 1 1)
					(thickness 0.15)
				)
				(justify mirror)
			)
		)
		(property "Dielectric" ""
			(at 258.2 183.8 0)
			(layer "B.Fab")
			(hide yes)
			(effects
				(font
					(size 1 1)
					(thickness 0.15)
				)
				(justify mirror)
			)
		)
		(property "License" "Apache-2.0"
			(at 258.2 183.8 0)
			(layer "B.Fab")
			(hide yes)
			(effects
				(font
					(size 1 1)
					(thickness 0.15)
				)
				(justify mirror)
			)
		)
		(property "MPN" "CC0201KRX6S5BB104"
			(at 258.2 183.8 0)
			(layer "B.Fab")
			(hide yes)
			(effects
				(font
					(size 1 1)
					(thickness 0.15)
				)
				(justify mirror)
			)
		)
		(property "Manufacturer" "YAGEO"
			(at 258.2 183.8 0)
			(layer "B.Fab")
			(hide yes)
			(effects
				(font
					(size 1 1)
					(thickness 0.15)
				)
				(justify mirror)
			)
		)
		(property "Val" "100n"
			(at 258.2 183.8 0)
			(layer "B.Fab")
			(hide yes)
			(effects
				(font
					(size 1 1)
					(thickness 0.15)
				)
				(justify mirror)
			)
		)
		(property "Voltage" ""
			(at 258.2 183.8 0)
			(layer "B.Fab")
			(hide yes)
			(effects
				(font
					(size 1 1)
					(thickness 0.15)
				)
				(justify mirror)
			)
		)
		(property "Public" "False"
			(at 0 0 180)
			(unlocked yes)
			(layer "B.Fab")
			(hide yes)
			(effects
				(font
					(size 1 1)
					(thickness 0.15)
				)
				(justify mirror)
			)
		)
		(sheetname "/SDI/")
		(sheetfile "sdi.kicad_sch")
		(attr smd)
		(fp_rect
			(start -0.7 0.35)
			(end 0.7 -0.35)
			(stroke
				(width 0.05)
				(type default)
			)
			(fill no)
			(layer "B.CrtYd")
		)
		(fp_rect
			(start 0.3 -0.15)
			(end -0.301 0.149)
			(stroke
				(width 0.15)
				(type solid)
			)
			(fill no)
			(layer "B.Fab")
		)
		(fp_text user "${REFERENCE}"
			(at -0.72 -3.4 0)
			(layer "B.Fab")
			(effects
				(font
					(size 0.7 0.7)
					(thickness 0.15)
				)
				(justify left bottom mirror)
			)
		)
		(fp_text user "Author: Antmicro"
			(at -0.72 -5.4 0)
			(layer "B.Fab")
			(effects
				(font
					(size 0.7 0.7)
					(thickness 0.15)
				)
				(justify left bottom mirror)
			)
		)
		(fp_text user "License: Apache-2.0"
			(at -0.72 -4.4 0)
			(layer "B.Fab")
			(effects
				(font
					(size 0.7 0.7)
					(thickness 0.15)
				)
				(justify left bottom mirror)
			)
		)
		(pad "" smd roundrect
			(at -0.349 0.002 180)
			(size 0.318 0.36)
			(layers "B.Paste")
			(roundrect_rratio 0.25)
		)
		(pad "" smd roundrect
			(at 0.341 0.002 180)
			(size 0.318 0.36)
			(layers "B.Paste")
			(roundrect_rratio 0.25)
		)
		(pad "1" smd roundrect
			(at -0.321 0.002 180)
			(size 0.46 0.4)
			(layers "B.Cu" "B.Mask")
			(roundrect_rratio 0.25)
			(net 1 "GND")
			(pintype "passive")
		)
		(pad "2" smd roundrect
			(at 0.32 0.002 180)
			(size 0.46 0.4)
			(layers "B.Cu" "B.Mask")
			(roundrect_rratio 0.25)
			(net 2 "+3V3")
			(pintype "passive")
		)
	)
	(footprint "antmicro-footprints:C_0402_1005Metric"
		(layer "B.Cu")
		(at 120.32 61.44 180)
		(descr "Capacitor SMD 0402")
		(tags "capacitor SMD 0402")
		(property "Reference" "C49"
			(at 0.99 -0.3 0)
			(layer "B.SilkS")
			(effects
				(font
					(size 0.65 0.65)
					(thickness 0.15)
				)
				(justify left bottom mirror)
			)
		)
		(property "Value" "C_100n_0402"
			(at 0 -1.4 0)
			(layer "B.Fab")
			(hide yes)
			(effects
				(font
					(size 0.7 0.7)
					(thickness 0.15)
				)
				(justify left bottom mirror)
			)
		)
		(property "Datasheet" "https://www.murata.com/products/productdetail?partno=GRM155R61H104KE14%23"
			(at 0 0 180)
			(layer "F.Fab")
			(hide yes)
			(effects
				(font
					(size 1.27 1.27)
					(thickness 0.15)
				)
			)
		)
		(property "Description" "SMD Multilayer Ceramic Capacitor, 0.1 µF, 50 V, 0402 [1005 Metric], ± 10%, X5R, GRM Series"
			(at 0 0 180)
			(layer "F.Fab")
			(hide yes)
			(effects
				(font
					(size 1.27 1.27)
					(thickness 0.15)
				)
			)
		)
		(property "Author" "Antmicro"
			(at 240.64 122.88 0)
			(layer "B.Fab")
			(hide yes)
			(effects
				(font
					(size 1 1)
					(thickness 0.15)
				)
				(justify mirror)
			)
		)
		(property "Dielectric" "X5R"
			(at 240.64 122.88 0)
			(layer "B.Fab")
			(hide yes)
			(effects
				(font
					(size 1 1)
					(thickness 0.15)
				)
				(justify mirror)
			)
		)
		(property "License" "Apache-2.0"
			(at 240.64 122.88 0)
			(layer "B.Fab")
			(hide yes)
			(effects
				(font
					(size 1 1)
					(thickness 0.15)
				)
				(justify mirror)
			)
		)
		(property "MPN" "GRM155R61H104KE14D"
			(at 240.64 122.88 0)
			(layer "B.Fab")
			(hide yes)
			(effects
				(font
					(size 1 1)
					(thickness 0.15)
				)
				(justify mirror)
			)
		)
		(property "Manufacturer" "Murata"
			(at 240.64 122.88 0)
			(layer "B.Fab")
			(hide yes)
			(effects
				(font
					(size 1 1)
					(thickness 0.15)
				)
				(justify mirror)
			)
		)
		(property "Val" "100n"
			(at 240.64 122.88 0)
			(layer "B.Fab")
			(hide yes)
			(effects
				(font
					(size 1 1)
					(thickness 0.15)
				)
				(justify mirror)
			)
		)
		(property "Voltage" "50V"
			(at 240.64 122.88 0)
			(layer "B.Fab")
			(hide yes)
			(effects
				(font
					(size 1 1)
					(thickness 0.15)
				)
				(justify mirror)
			)
		)
		(sheetname "/DDR3/")
		(sheetfile "ddr3.kicad_sch")
		(attr smd)
		(fp_rect
			(start -0.925 0.47)
			(end 0.925 -0.47)
			(stroke
				(width 0.05)
				(type default)
			)
			(fill no)
			(layer "B.CrtYd")
		)
		(fp_line
			(start 0.504 0.25)
			(end 0.504 -0.248)
			(stroke
				(width 0.15)
				(type solid)
			)
			(layer "B.Fab")
		)
		(fp_line
			(start 0.504 -0.248)
			(end -0.494 -0.248)
			(stroke
				(width 0.15)
				(type solid)
			)
			(layer "B.Fab")
		)
		(fp_line
			(start -0.494 0.25)
			(end 0.504 0.25)
			(stroke
				(width 0.15)
				(type solid)
			)
			(layer "B.Fab")
		)
		(fp_line
			(start -0.494 -0.248)
			(end -0.494 0.25)
			(stroke
				(width 0.15)
				(type solid)
			)
			(layer "B.Fab")
		)
		(fp_text user "Author: Antmicro"
			(at -0.939 -3.399 0)
			(layer "B.Fab")
			(effects
				(font
					(size 0.7 0.7)
					(thickness 0.15)
				)
				(justify left bottom mirror)
			)
		)
		(fp_text user "License: Apache-2.0"
			(at -0.939 -5.799 0)
			(layer "B.Fab")
			(effects
				(font
					(size 0.7 0.7)
					(thickness 0.15)
				)
				(justify left bottom mirror)
			)
		)
		(fp_text user "${REFERENCE}"
			(at -0.939 -4.599 0)
			(layer "B.Fab")
			(effects
				(font
					(size 0.7 0.7)
					(thickness 0.15)
				)
				(justify left bottom mirror)
			)
		)
		(pad "1" smd roundrect
			(at -0.48 0 180)
			(size 0.59 0.64)
			(layers "B.Cu" "B.Mask" "B.Paste")
			(roundrect_rratio 0.25)
			(net 5 "Vref")
			(pintype "passive")
		)
		(pad "2" smd roundrect
			(at 0.48 0 180)
			(size 0.59 0.64)
			(layers "B.Cu" "B.Mask" "B.Paste")
			(roundrect_rratio 0.25)
			(net 248 "+1V5")
			(pintype "passive")
		)
	)
	(footprint "antmicro-footprints:C_0402_1005Metric"
		(layer "B.Cu")
		(at 95.58 75.07 -90)
		(descr "Capacitor SMD 0402")
		(tags "capacitor SMD 0402")
		(property "Reference" "C70"
			(at -0.93 0.55 90)
			(layer "B.SilkS")
			(effects
				(font
					(size 0.65 0.65)
					(thickness 0.15)
				)
				(justify left bottom mirror)
			)
		)
		(property "Value" "C_100n_0402"
			(at 0 -1.4 90)
			(layer "B.Fab")
			(hide yes)
			(effects
				(font
					(size 0.7 0.7)
					(thickness 0.15)
				)
				(justify left bottom mirror)
			)
		)
		(property "Datasheet" "https://www.murata.com/products/productdetail?partno=GRM155R61H104KE14%23"
			(at 0 0 270)
			(layer "F.Fab")
			(hide yes)
			(effects
				(font
					(size 1.27 1.27)
					(thickness 0.15)
				)
			)
		)
		(property "Description" "SMD Multilayer Ceramic Capacitor, 0.1 µF, 50 V, 0402 [1005 Metric], ± 10%, X5R, GRM Series"
			(at 0 0 270)
			(layer "F.Fab")
			(hide yes)
			(effects
				(font
					(size 1.27 1.27)
					(thickness 0.15)
				)
			)
		)
		(property "Author" "Antmicro"
			(at 20.51 170.65 0)
			(layer "B.Fab")
			(hide yes)
			(effects
				(font
					(size 1 1)
					(thickness 0.15)
				)
				(justify mirror)
			)
		)
		(property "Dielectric" "X5R"
			(at 20.51 170.65 0)
			(layer "B.Fab")
			(hide yes)
			(effects
				(font
					(size 1 1)
					(thickness 0.15)
				)
				(justify mirror)
			)
		)
		(property "License" "Apache-2.0"
			(at 20.51 170.65 0)
			(layer "B.Fab")
			(hide yes)
			(effects
				(font
					(size 1 1)
					(thickness 0.15)
				)
				(justify mirror)
			)
		)
		(property "MPN" "GRM155R61H104KE14D"
			(at 20.51 170.65 0)
			(layer "B.Fab")
			(hide yes)
			(effects
				(font
					(size 1 1)
					(thickness 0.15)
				)
				(justify mirror)
			)
		)
		(property "Manufacturer" "Murata"
			(at 20.51 170.65 0)
			(layer "B.Fab")
			(hide yes)
			(effects
				(font
					(size 1 1)
					(thickness 0.15)
				)
				(justify mirror)
			)
		)
		(property "Val" "100n"
			(at 20.51 170.65 0)
			(layer "B.Fab")
			(hide yes)
			(effects
				(font
					(size 1 1)
					(thickness 0.15)
				)
				(justify mirror)
			)
		)
		(property "Voltage" "50V"
			(at 20.51 170.65 0)
			(layer "B.Fab")
			(hide yes)
			(effects
				(font
					(size 1 1)
					(thickness 0.15)
				)
				(justify mirror)
			)
		)
		(sheetname "/SDI/")
		(sheetfile "sdi.kicad_sch")
		(attr smd)
		(fp_rect
			(start -0.925 0.47)
			(end 0.925 -0.47)
			(stroke
				(width 0.05)
				(type default)
			)
			(fill no)
			(layer "B.CrtYd")
		)
		(fp_line
			(start -0.494 0.25)
			(end 0.504 0.25)
			(stroke
				(width 0.15)
				(type solid)
			)
			(layer "B.Fab")
		)
		(fp_line
			(start 0.504 0.25)
			(end 0.504 -0.248)
			(stroke
				(width 0.15)
				(type solid)
			)
			(layer "B.Fab")
		)
		(fp_line
			(start -0.494 -0.248)
			(end -0.494 0.25)
			(stroke
				(width 0.15)
				(type solid)
			)
			(layer "B.Fab")
		)
		(fp_line
			(start 0.504 -0.248)
			(end -0.494 -0.248)
			(stroke
				(width 0.15)
				(type solid)
			)
			(layer "B.Fab")
		)
		(fp_text user "${REFERENCE}"
			(at -0.939 -4.599 90)
			(layer "B.Fab")
			(effects
				(font
					(size 0.7 0.7)
					(thickness 0.15)
				)
				(justify left bottom mirror)
			)
		)
		(fp_text user "Author: Antmicro"
			(at -0.939 -3.399 90)
			(layer "B.Fab")
			(effects
				(font
					(size 0.7 0.7)
					(thickness 0.15)
				)
				(justify left bottom mirror)
			)
		)
		(fp_text user "License: Apache-2.0"
			(at -0.939 -5.799 90)
			(layer "B.Fab")
			(effects
				(font
					(size 0.7 0.7)
					(thickness 0.15)
				)
				(justify left bottom mirror)
			)
		)
		(pad "1" smd roundrect
			(at -0.48 0 270)
			(size 0.59 0.64)
			(layers "B.Cu" "B.Mask" "B.Paste")
			(roundrect_rratio 0.25)
			(net 1 "GND")
			(pintype "passive")
		)
		(pad "2" smd roundrect
			(at 0.48 0 270)
			(size 0.59 0.64)
			(layers "B.Cu" "B.Mask" "B.Paste")
			(roundrect_rratio 0.25)
			(net 3 "+1V2")
			(pintype "passive")
		)
	)
	(footprint "antmicro-footprints:TP_SMD_0.75mm"
		(layer "B.Cu")
		(at 95.44 88.2 90)
		(property "Reference" "TP43"
			(at 0.76 0.39 90)
			(layer "B.SilkS")
			(effects
				(font
					(size 0.65 0.65)
					(thickness 0.15)
				)
				(justify right bottom mirror)
			)
		)
		(property "Value" "TP_0.75mm_SMD"
			(at 0 -1.2 90)
			(layer "B.Fab")
			(hide yes)
			(effects
				(font
					(size 0.7 0.7)
					(thickness 0.15)
				)
				(justify right bottom mirror)
			)
		)
		(property "Description" "SMT test point"
			(at 0 0 90)
			(layer "F.Fab")
			(hide yes)
			(effects
				(font
					(size 1.27 1.27)
					(thickness 0.15)
				)
			)
		)
		(property "Author" "Antmicro"
			(at 183.64 -7.24 0)
			(layer "B.Fab")
			(hide yes)
			(effects
				(font
					(size 1 1)
					(thickness 0.15)
				)
				(justify mirror)
			)
		)
		(property "License" "Apache-2.0"
			(at 183.64 -7.24 0)
			(layer "B.Fab")
			(hide yes)
			(effects
				(font
					(size 1 1)
					(thickness 0.15)
				)
				(justify mirror)
			)
		)
		(property "MPN" ""
			(at 183.64 -7.24 0)
			(layer "B.Fab")
			(hide yes)
			(effects
				(font
					(size 1 1)
					(thickness 0.15)
				)
				(justify mirror)
			)
		)
		(property "Manufacturer" ""
			(at 183.64 -7.24 0)
			(layer "B.Fab")
			(hide yes)
			(effects
				(font
					(size 1 1)
					(thickness 0.15)
				)
				(justify mirror)
			)
		)
		(sheetname "/SDI/")
		(sheetfile "sdi.kicad_sch")
		(attr exclude_from_pos_files)
		(fp_circle
			(center 0 0)
			(end 0.475 0)
			(stroke
				(width 0.05)
				(type default)
			)
			(fill no)
			(layer "B.CrtYd")
		)
		(fp_text user "${REFERENCE}"
			(at -0.4 -2.7 270)
			(layer "B.Fab")
			(effects
				(font
					(size 0.7 0.7)
					(thickness 0.15)
				)
				(justify left bottom mirror)
			)
		)
		(fp_text user "Author: Antmicro"
			(at -0.4 -3.901 270)
			(layer "B.Fab")
			(effects
				(font
					(size 0.7 0.7)
					(thickness 0.15)
				)
				(justify left bottom mirror)
			)
		)
		(fp_text user "License: Apache-2.0"
			(at -0.4 -5.101 270)
			(layer "B.Fab")
			(effects
				(font
					(size 0.7 0.7)
					(thickness 0.15)
				)
				(justify left bottom mirror)
			)
		)
		(pad "1" smd circle
			(at 0 0 90)
			(size 0.75 0.75)
			(layers "B.Cu" "B.Mask")
			(net 181 "/SDI/SDOUT_TDO")
			(pinfunction "1")
			(pintype "passive")
		)
	)
	(footprint "antmicro-footprints:C_0603_1608Metric"
		(layer "B.Cu")
		(at 134.39 95.48)
		(descr "Capacitor SMD 0603")
		(tags "capacitor 0603")
		(property "Reference" "C90"
			(at -0.86 -0.84 0)
			(layer "B.SilkS")
			(effects
				(font
					(size 0.65 0.65)
					(thickness 0.15)
				)
				(justify right bottom mirror)
			)
		)
		(property "Value" "C_10u_0603"
			(at 0 -1.6 0)
			(layer "B.Fab")
			(hide yes)
			(effects
				(font
					(size 0.7 0.7)
					(thickness 0.15)
				)
				(justify right bottom mirror)
			)
		)
		(property "Datasheet" "https://www.murata.com/products/productdetail?partno=GRM188R61A106KE69%23"
			(at 0 0 0)
			(layer "F.Fab")
			(hide yes)
			(effects
				(font
					(size 1.27 1.27)
					(thickness 0.15)
				)
			)
		)
		(property "Description" "SMD Multilayer Ceramic Capacitor, 10 µF, 10 V, 0603 [1608 Metric], ± 10%, X5R, GRM Series"
			(at 0 0 0)
			(layer "F.Fab")
			(hide yes)
			(effects
				(font
					(size 1.27 1.27)
					(thickness 0.15)
				)
			)
		)
		(property "Author" "Antmicro"
			(at 0 0 0)
			(layer "B.Fab")
			(hide yes)
			(effects
				(font
					(size 1 1)
					(thickness 0.15)
				)
				(justify mirror)
			)
		)
		(property "License" "Apache-2.0"
			(at 0 0 0)
			(layer "B.Fab")
			(hide yes)
			(effects
				(font
					(size 1 1)
					(thickness 0.15)
				)
				(justify mirror)
			)
		)
		(property "MPN" "GRM188R61A106KE69D"
			(at 0 0 0)
			(layer "B.Fab")
			(hide yes)
			(effects
				(font
					(size 1 1)
					(thickness 0.15)
				)
				(justify mirror)
			)
		)
		(property "Manufacturer" "Murata"
			(at 0 0 0)
			(layer "B.Fab")
			(hide yes)
			(effects
				(font
					(size 1 1)
					(thickness 0.15)
				)
				(justify mirror)
			)
		)
		(property "Val" "10u"
			(at 0 0 0)
			(layer "B.Fab")
			(hide yes)
			(effects
				(font
					(size 1 1)
					(thickness 0.15)
				)
				(justify mirror)
			)
		)
		(property "Voltage" ""
			(at 0 0 0)
			(layer "B.Fab")
			(hide yes)
			(effects
				(font
					(size 1 1)
					(thickness 0.15)
				)
				(justify mirror)
			)
		)
		(property "Dielectric" "template_dielectric"
			(at 0 0 0)
			(unlocked yes)
			(layer "B.Fab")
			(hide yes)
			(effects
				(font
					(size 1 1)
					(thickness 0.15)
				)
				(justify mirror)
			)
		)
		(sheetname "/FPGA Power/")
		(sheetfile "FPGA_Power.kicad_sch")
		(attr smd)
		(fp_line
			(start -0.15 -0.4)
			(end 0.15 -0.4)
			(stroke
				(width 0.15)
				(type solid)
			)
			(layer "B.SilkS")
		)
		(fp_line
			(start -0.15 0.4)
			(end 0.15 0.4)
			(stroke
				(width 0.15)
				(type solid)
			)
			(layer "B.SilkS")
		)
		(fp_rect
			(start -1.25 0.65)
			(end 1.25 -0.65)
			(stroke
				(width 0.05)
				(type solid)
			)
			(fill no)
			(layer "B.CrtYd")
		)
		(fp_rect
			(start -0.8 0.4)
			(end 0.8 -0.4)
			(stroke
				(width 0.15)
				(type solid)
			)
			(fill no)
			(layer "B.Fab")
		)
		(fp_text user "${REFERENCE}"
			(at -1.682 -3.895 180)
			(layer "B.Fab")
			(effects
				(font
					(size 0.7 0.7)
					(thickness 0.15)
				)
				(justify left bottom mirror)
			)
		)
		(fp_text user "License: Apache-2.0"
			(at -1.682 -5.895 180)
			(layer "B.Fab")
			(effects
				(font
					(size 0.7 0.7)
					(thickness 0.15)
				)
				(justify left bottom mirror)
			)
		)
		(fp_text user "Author: Antmicro"
			(at -1.682 -4.894 180)
			(layer "B.Fab")
			(effects
				(font
					(size 0.7 0.7)
					(thickness 0.15)
				)
				(justify left bottom mirror)
			)
		)
		(pad "1" smd roundrect
			(at -0.7 0)
			(size 0.8 1)
			(layers "B.Cu" "B.Mask" "B.Paste")
			(roundrect_rratio 0.2)
			(net 1 "GND")
			(pintype "passive")
		)
		(pad "2" smd roundrect
			(at 0.7 0)
			(size 0.8 1)
			(layers "B.Cu" "B.Mask" "B.Paste")
			(roundrect_rratio 0.2)
			(net 12 "/FPGA Power/VCC_ADPHY")
			(pintype "passive")
		)
	)
)
